(kicad_pcb
	(version 20260206)
	(generator "pcbnew")
	(generator_version "10.0")
	(general
		(thickness 1.6)
		(legacy_teardrops no)
	)
	(paper "A4")
	(title_block
		(title "03242023_DA0F0TMBIJ0_F0T_Motherboard_J_brd_V01_OCP.brd")
		(comment 1 "Grand Teton / footprint 1682 of 6105 (U1), pads 2584-2694 of 4677")
	)
	(layers
		(0 "F.Cu" signal "TOP")
		(4 "In1.Cu" signal "GND")
		(6 "In2.Cu" signal "IN1")
		(8 "In3.Cu" signal "GND1")
		(10 "In4.Cu" signal "IN2")
		(12 "In5.Cu" signal "GND2")
		(14 "In6.Cu" signal "IN3")
		(16 "In7.Cu" signal "GND3")
		(18 "In8.Cu" signal "VCC")
		(20 "In9.Cu" signal "VCC1")
		(22 "In10.Cu" signal "GND4")
		(24 "In11.Cu" signal "IN4")
		(26 "In12.Cu" signal "GND5")
		(28 "In13.Cu" signal "IN5")
		(30 "In14.Cu" signal "GND6")
		(32 "In15.Cu" signal "IN6")
		(34 "In16.Cu" signal "GND7")
		(2 "B.Cu" signal "BOTTOM")
		(9 "F.Adhes" user "F.Adhesive")
		(11 "B.Adhes" user "B.Adhesive")
		(13 "F.Paste" user "Package Geometry/Pastemask Top")
		(15 "B.Paste" user "Package Geometry/Pastemask Bottom")
		(5 "F.SilkS" user "Ref Des/Silkscreen Top")
		(7 "B.SilkS" user "Ref Des/Silkscreen Bottom")
		(1 "F.Mask" user "Board Geometry/Soldermask Top")
		(3 "B.Mask" user "Board Geometry/Soldermask Bottom")
		(17 "Dwgs.User" user "User.Drawings")
		(19 "Cmts.User" user "User.Comments")
		(21 "Eco1.User" user "User.Eco1")
		(23 "Eco2.User" user "User.Eco2")
		(25 "Edge.Cuts" user "Board Geometry/Outline")
		(27 "Margin" user)
		(31 "F.CrtYd" user "Package Geometry/Place Bound Top")
		(29 "B.CrtYd" user "Package Geometry/Place Bound Bottom")
		(35 "F.Fab" user "Ref Des/Assembly Top")
		(33 "B.Fab" user "Ref Des/Assembly Bottom")
	)
	(footprint ""
		(layer "F.Cu")
		(at 111.93018 -251.76988 90)
		(property "Reference" "U1"
			(at -74.913236 41.548812 0)
			(unlocked yes)
			(layer "F.SilkS")
			(effects
				(font
					(size 1.6002 1.1938)
					(thickness 0.1524)
				)
				(justify left)
			)
		)
		(property "Value" ""
			(at 0 0 90)
			(layer "F.Fab")
			(effects
				(font
					(size 1.27 1.27)
				)
			)
		)
		(duplicate_pad_numbers_are_jumpers no)
		(pad "DE27" smd circle
			(at -16.263874 12.397486 270)
			(size 0.4318 0.4318)
			(layers "F.Cu" "F.Mask" "F.Paste")
			(net "GND")
		)
		(pad "DE29" smd circle
			(at -14.635988 12.397486 270)
			(size 0.4318 0.4318)
			(layers "F.Cu" "F.Mask" "F.Paste")
			(net "GND")
		)
		(pad "DE31" smd circle
			(at -13.008356 12.397486 270)
			(size 0.4318 0.4318)
			(layers "F.Cu" "F.Mask" "F.Paste")
			(net "GND")
		)
		(pad "DE33" smd circle
			(at -11.380724 12.397486 270)
			(size 0.4318 0.4318)
			(layers "F.Cu" "F.Mask" "F.Paste")
			(net "GND")
		)
		(pad "DE35" smd circle
			(at -9.752838 12.397486 270)
			(size 0.4318 0.4318)
			(layers "F.Cu" "F.Mask" "F.Paste")
			(net "GND")
		)
		(pad "DE37" smd circle
			(at -8.124952 12.397486 270)
			(size 0.4318 0.4318)
			(layers "F.Cu" "F.Mask" "F.Paste")
			(net "GND")
		)
		(pad "DE39" smd circle
			(at -6.49732 12.397486 270)
			(size 0.4318 0.4318)
			(layers "F.Cu" "F.Mask" "F.Paste")
			(net "GND")
		)
		(pad "DE41" smd circle
			(at -4.869434 12.397486 270)
			(size 0.4318 0.4318)
			(layers "F.Cu" "F.Mask" "F.Paste")
			(net "GND")
		)
		(pad "DE43" smd circle
			(at -3.241802 12.397486 270)
			(size 0.4318 0.4318)
			(layers "F.Cu" "F.Mask" "F.Paste")
			(net "GND")
		)
		(pad "DE45" smd circle
			(at -1.613916 12.397486 270)
			(size 0.4318 0.4318)
			(layers "F.Cu" "F.Mask" "F.Paste")
			(net "GND")
		)
		(pad "DE48" smd circle
			(at 2.427732 12.507468 270)
			(size 0.4318 0.4318)
			(layers "F.Cu" "F.Mask" "F.Paste")
			(net "GND")
		)
		(pad "DE50" smd circle
			(at 4.055618 12.507468 270)
			(size 0.4318 0.4318)
			(layers "F.Cu" "F.Mask" "F.Paste")
			(net "GND")
		)
		(pad "DE52" smd circle
			(at 5.68325 12.507468 270)
			(size 0.4318 0.4318)
			(layers "F.Cu" "F.Mask" "F.Paste")
			(net "GND")
		)
		(pad "DE54" smd circle
			(at 7.311136 12.507468 270)
			(size 0.4318 0.4318)
			(layers "F.Cu" "F.Mask" "F.Paste")
			(net "GND")
		)
		(pad "DE56" smd circle
			(at 8.939022 12.507468 270)
			(size 0.4318 0.4318)
			(layers "F.Cu" "F.Mask" "F.Paste")
			(net "GND")
		)
		(pad "DE58" smd circle
			(at 10.566654 12.507468 270)
			(size 0.4318 0.4318)
			(layers "F.Cu" "F.Mask" "F.Paste")
			(net "GND")
		)
		(pad "DE60" smd circle
			(at 12.19454 12.507468 270)
			(size 0.4318 0.4318)
			(layers "F.Cu" "F.Mask" "F.Paste")
			(net "GND")
		)
		(pad "DE62" smd circle
			(at 13.822426 12.507468 270)
			(size 0.4318 0.4318)
			(layers "F.Cu" "F.Mask" "F.Paste")
			(net "GND")
		)
		(pad "DE64" smd circle
			(at 15.450058 12.507468 270)
			(size 0.4318 0.4318)
			(layers "F.Cu" "F.Mask" "F.Paste")
			(net "GND")
		)
		(pad "DE66" smd circle
			(at 17.07769 12.507468 270)
			(size 0.4318 0.4318)
			(layers "F.Cu" "F.Mask" "F.Paste")
			(net "GND")
		)
		(pad "DE68" smd circle
			(at 18.705576 12.507468 270)
			(size 0.4318 0.4318)
			(layers "F.Cu" "F.Mask" "F.Paste")
			(net "GND")
		)
		(pad "DE70" smd circle
			(at 20.333462 12.507468 270)
			(size 0.4318 0.4318)
			(layers "F.Cu" "F.Mask" "F.Paste")
			(net "GND")
		)
		(pad "DE72" smd circle
			(at 21.961094 12.507468 270)
			(size 0.4318 0.4318)
			(layers "F.Cu" "F.Mask" "F.Paste")
			(net "GND")
		)
		(pad "DE74" smd circle
			(at 23.58898 12.507468 270)
			(size 0.4318 0.4318)
			(layers "F.Cu" "F.Mask" "F.Paste")
			(net "GND")
		)
		(pad "DE76" smd circle
			(at 25.216612 12.507468 270)
			(size 0.4318 0.4318)
			(layers "F.Cu" "F.Mask" "F.Paste")
			(net "GND")
		)
		(pad "DE78" smd circle
			(at 26.844498 12.507468 270)
			(size 0.4318 0.4318)
			(layers "F.Cu" "F.Mask" "F.Paste")
			(net "GND")
		)
		(pad "DE80" smd circle
			(at 28.472384 12.507468 270)
			(size 0.4318 0.4318)
			(layers "F.Cu" "F.Mask" "F.Paste")
			(net "GND")
		)
		(pad "DE82" smd circle
			(at 30.100016 12.507468 270)
			(size 0.4318 0.4318)
			(layers "F.Cu" "F.Mask" "F.Paste")
			(net "GND")
		)
		(pad "DE84" smd circle
			(at 31.727902 12.507468 270)
			(size 0.4318 0.4318)
			(layers "F.Cu" "F.Mask" "F.Paste")
			(net "GND")
		)
		(pad "DE86" smd circle
			(at 33.355534 12.507468 270)
			(size 0.4318 0.4318)
			(layers "F.Cu" "F.Mask" "F.Paste")
			(net "P5E_CPU1_PE3_TX_DP<10>")
		)
		(pad "DE88" smd circle
			(at 34.98342 12.507468 270)
			(size 0.4318 0.4318)
			(layers "F.Cu" "F.Mask" "F.Paste")
			(net "GND")
		)
		(pad "DE90" smd circle
			(at 36.611306 12.507468 270)
			(size 0.4318 0.4318)
			(layers "F.Cu" "F.Mask" "F.Paste")
			(net "P5E_CPU1_PE3_RX_DP<11>")
		)
		(pad "DF2" smd circle
			(at -36.611306 12.867132 270)
			(size 0.4318 0.4318)
			(layers "F.Cu" "F.Mask" "F.Paste")
			(net "UPI_CPU0_CPU1_P0P1_DP<11>")
		)
		(pad "DF4" smd circle
			(at -34.98342 12.867132 270)
			(size 0.4318 0.4318)
			(layers "F.Cu" "F.Mask" "F.Paste")
			(net "GND")
		)
		(pad "DF6" smd circle
			(at -33.355534 12.867132 270)
			(size 0.4318 0.4318)
			(layers "F.Cu" "F.Mask" "F.Paste")
			(net "UPI_CPU1_CPU0_P1P0_DP<10>")
		)
		(pad "DF8" smd circle
			(at -31.727902 12.867132 270)
			(size 0.4318 0.4318)
			(layers "F.Cu" "F.Mask" "F.Paste")
			(net "GND")
		)
		(pad "DF10" smd circle
			(at -30.100016 12.867132 270)
			(size 0.4318 0.4318)
			(layers "F.Cu" "F.Mask" "F.Paste")
			(net "P5E_CPU1_PE2_RX_DP<4>")
		)
		(pad "DF12" smd circle
			(at -28.472384 12.867132 270)
			(size 0.4318 0.4318)
			(layers "F.Cu" "F.Mask" "F.Paste")
			(net "GND")
		)
		(pad "DF14" smd circle
			(at -26.844498 12.867132 270)
			(size 0.4318 0.4318)
			(layers "F.Cu" "F.Mask" "F.Paste")
			(net "P5E_CPU1_PE2_TX_DN<5>")
		)
		(pad "DF16" smd circle
			(at -25.216612 12.867132 270)
			(size 0.4318 0.4318)
			(layers "F.Cu" "F.Mask" "F.Paste")
			(net "GND")
		)
		(pad "DF18" smd circle
			(at -23.58898 12.867132 270)
			(size 0.4318 0.4318)
			(layers "F.Cu" "F.Mask" "F.Paste")
			(net "M_H_CPU1_SB_DQS_DN<8>")
		)
		(pad "DF20" smd circle
			(at -21.961094 12.867132 270)
			(size 0.4318 0.4318)
			(layers "F.Cu" "F.Mask" "F.Paste")
			(net "M_H_CPU1_SB_DQ<26>")
		)
		(pad "DF22" smd circle
			(at -20.333462 12.867132 270)
			(size 0.4318 0.4318)
			(layers "F.Cu" "F.Mask" "F.Paste")
			(net "M_H_CPU1_SB_DQ<15>")
		)
		(pad "DF24" smd circle
			(at -18.705576 12.867132 270)
			(size 0.4318 0.4318)
			(layers "F.Cu" "F.Mask" "F.Paste")
			(net "M_H_CPU1_SB_DQS_DP<6>")
		)
		(pad "DF26" smd circle
			(at -17.07769 12.867132 270)
			(size 0.4318 0.4318)
			(layers "F.Cu" "F.Mask" "F.Paste")
			(net "M_H_CPU1_SB_DQ<10>")
		)
		(pad "DF28" smd circle
			(at -15.450058 12.867132 270)
			(size 0.4318 0.4318)
			(layers "F.Cu" "F.Mask" "F.Paste")
			(net "M_H_CPU1_SB_DQ<5>")
		)
		(pad "DF30" smd circle
			(at -13.822426 12.867132 270)
			(size 0.4318 0.4318)
			(layers "F.Cu" "F.Mask" "F.Paste")
			(net "M_H_CPU1_SB_DQS_DP<5>")
		)
		(pad "DF32" smd circle
			(at -12.19454 12.867132 270)
			(size 0.4318 0.4318)
			(layers "F.Cu" "F.Mask" "F.Paste")
			(net "M_H_CPU1_SB_DQ<2>")
		)
		(pad "DF34" smd circle
			(at -10.566654 12.867132 270)
			(size 0.4318 0.4318)
			(layers "F.Cu" "F.Mask" "F.Paste")
			(net "M_H_CPU1_SB_CB<3>")
		)
		(pad "DF36" smd circle
			(at -8.939022 12.867132 270)
			(size 0.4318 0.4318)
			(layers "F.Cu" "F.Mask" "F.Paste")
			(net "M_H_CPU1_SB_DQS_DP<4>")
		)
		(pad "DF38" smd circle
			(at -7.311136 12.867132 270)
			(size 0.4318 0.4318)
			(layers "F.Cu" "F.Mask" "F.Paste")
			(net "M_H_CPU1_SB_CB<4>")
		)
		(pad "DF40" smd circle
			(at -5.68325 12.867132 270)
			(size 0.4318 0.4318)
			(layers "F.Cu" "F.Mask" "F.Paste")
			(net "M_H_CPU1_SB_CA<0>")
		)
		(pad "DF42" smd circle
			(at -4.055618 12.867132 270)
			(size 0.4318 0.4318)
			(layers "F.Cu" "F.Mask" "F.Paste")
			(net "M_H_CPU1_CLK_DP<0>")
		)
		(pad "DF44" smd circle
			(at -2.427732 12.867132 270)
			(size 0.4318 0.4318)
			(layers "F.Cu" "F.Mask" "F.Paste")
			(net "M_E_CPU1_SB_RSP<0>")
		)
		(pad "DF47" smd circle
			(at 1.613916 12.977114 270)
			(size 0.4318 0.4318)
			(layers "F.Cu" "F.Mask" "F.Paste")
			(net "M_H_CPU1_SA_CA<5>")
		)
		(pad "DF49" smd circle
			(at 3.241802 12.977114 270)
			(size 0.4318 0.4318)
			(layers "F.Cu" "F.Mask" "F.Paste")
			(net "GND")
		)
		(pad "DF51" smd circle
			(at 4.869434 12.977114 270)
			(size 0.4318 0.4318)
			(layers "F.Cu" "F.Mask" "F.Paste")
			(net "M_H_CPU1_SA_CS_N<0>")
		)
		(pad "DF53" smd circle
			(at 6.49732 12.977114 270)
			(size 0.4318 0.4318)
			(layers "F.Cu" "F.Mask" "F.Paste")
			(net "M_H_CPU1_SA_CB<7>")
		)
		(pad "DF55" smd circle
			(at 8.124952 12.977114 270)
			(size 0.4318 0.4318)
			(layers "F.Cu" "F.Mask" "F.Paste")
			(net "M_H_CPU1_SA_DQS_DP<9>")
		)
		(pad "DF57" smd circle
			(at 9.752838 12.977114 270)
			(size 0.4318 0.4318)
			(layers "F.Cu" "F.Mask" "F.Paste")
			(net "M_H_CPU1_SA_CB<2>")
		)
		(pad "DF59" smd circle
			(at 11.380724 12.977114 270)
			(size 0.4318 0.4318)
			(layers "F.Cu" "F.Mask" "F.Paste")
			(net "M_H_CPU1_SA_DQ<31>")
		)
		(pad "DF61" smd circle
			(at 13.008356 12.977114 270)
			(size 0.4318 0.4318)
			(layers "F.Cu" "F.Mask" "F.Paste")
			(net "M_H_CPU1_SA_DQS_DP<8>")
		)
		(pad "DF63" smd circle
			(at 14.635988 12.977114 270)
			(size 0.4318 0.4318)
			(layers "F.Cu" "F.Mask" "F.Paste")
			(net "M_H_CPU1_SA_DQ<26>")
		)
		(pad "DF65" smd circle
			(at 16.263874 12.977114 270)
			(size 0.4318 0.4318)
			(layers "F.Cu" "F.Mask" "F.Paste")
			(net "M_H_CPU1_SA_DQ<23>")
		)
		(pad "DF67" smd circle
			(at 17.89176 12.977114 270)
			(size 0.4318 0.4318)
			(layers "F.Cu" "F.Mask" "F.Paste")
			(net "M_H_CPU1_SA_DQS_DP<7>")
		)
		(pad "DF69" smd circle
			(at 19.519392 12.977114 270)
			(size 0.4318 0.4318)
			(layers "F.Cu" "F.Mask" "F.Paste")
			(net "M_H_CPU1_SA_DQ<18>")
		)
		(pad "DF71" smd circle
			(at 21.147278 12.977114 270)
			(size 0.4318 0.4318)
			(layers "F.Cu" "F.Mask" "F.Paste")
			(net "M_H_CPU1_SA_DQ<15>")
		)
		(pad "DF73" smd circle
			(at 22.77491 12.977114 270)
			(size 0.4318 0.4318)
			(layers "F.Cu" "F.Mask" "F.Paste")
			(net "M_H_CPU1_SA_DQS_DP<6>")
		)
		(pad "DF75" smd circle
			(at 24.402796 12.977114 270)
			(size 0.4318 0.4318)
			(layers "F.Cu" "F.Mask" "F.Paste")
			(net "M_H_CPU1_SA_DQ<10>")
		)
		(pad "DF77" smd circle
			(at 26.030682 12.977114 270)
			(size 0.4318 0.4318)
			(layers "F.Cu" "F.Mask" "F.Paste")
			(net "GND")
		)
		(pad "DF79" smd circle
			(at 27.658314 12.977114 270)
			(size 0.4318 0.4318)
			(layers "F.Cu" "F.Mask" "F.Paste")
			(net "GND")
		)
		(pad "DF81" smd circle
			(at 29.2862 12.977114 270)
			(size 0.4318 0.4318)
			(layers "F.Cu" "F.Mask" "F.Paste")
			(net "GND")
		)
		(pad "DF83" smd circle
			(at 30.914086 12.977114 270)
			(size 0.4318 0.4318)
			(layers "F.Cu" "F.Mask" "F.Paste")
			(net "GND")
		)
		(pad "DF85" smd circle
			(at 32.541718 12.977114 270)
			(size 0.4318 0.4318)
			(layers "F.Cu" "F.Mask" "F.Paste")
			(net "P5E_CPU1_PE3_TX_DN<9>")
		)
		(pad "DF87" smd circle
			(at 34.169604 12.977114 270)
			(size 0.4318 0.4318)
			(layers "F.Cu" "F.Mask" "F.Paste")
			(net "GND")
		)
		(pad "DF89" smd circle
			(at 35.797236 12.977114 270)
			(size 0.4318 0.4318)
			(layers "F.Cu" "F.Mask" "F.Paste")
			(net "P5E_CPU1_PE3_RX_DP<10>")
		)
		(pad "DF91" smd oval
			(at 37.425122 12.977114)
			(size 0.381 0.4826)
			(drill
				(offset 0 -0.0508)
			)
			(layers "F.Cu" "F.Mask" "F.Paste")
			(net "GND")
		)
		(pad "DG1" smd oval
			(at -37.425122 13.337286 180)
			(size 0.381 0.4826)
			(drill
				(offset 0 -0.0508)
			)
			(layers "F.Cu" "F.Mask" "F.Paste")
			(net "GND")
		)
		(pad "DG3" smd circle
			(at -35.797236 13.337286 270)
			(size 0.4318 0.4318)
			(layers "F.Cu" "F.Mask" "F.Paste")
			(net "UPI_CPU0_CPU1_P0P1_DN<10>")
		)
		(pad "DG5" smd circle
			(at -34.169604 13.337286 270)
			(size 0.4318 0.4318)
			(layers "F.Cu" "F.Mask" "F.Paste")
			(net "GND")
		)
		(pad "DG7" smd circle
			(at -32.541718 13.337286 270)
			(size 0.4318 0.4318)
			(layers "F.Cu" "F.Mask" "F.Paste")
			(net "UPI_CPU1_CPU0_P1P0_DP<9>")
		)
		(pad "DG9" smd circle
			(at -30.914086 13.337286 270)
			(size 0.4318 0.4318)
			(layers "F.Cu" "F.Mask" "F.Paste")
			(net "GND")
		)
		(pad "DG11" smd circle
			(at -29.2862 13.337286 270)
			(size 0.4318 0.4318)
			(layers "F.Cu" "F.Mask" "F.Paste")
			(net "P5E_CPU1_PE2_RX_DP<5>")
		)
		(pad "DG13" smd circle
			(at -27.658314 13.337286 270)
			(size 0.4318 0.4318)
			(layers "F.Cu" "F.Mask" "F.Paste")
			(net "GND")
		)
		(pad "DG15" smd circle
			(at -26.030682 13.337286 270)
			(size 0.4318 0.4318)
			(layers "F.Cu" "F.Mask" "F.Paste")
			(net "P5E_CPU1_PE2_TX_DP<5>")
		)
		(pad "DG17" smd circle
			(at -24.402796 13.337286 270)
			(size 0.4318 0.4318)
			(layers "F.Cu" "F.Mask" "F.Paste")
			(net "M_H_CPU1_SB_DQ<28>")
		)
		(pad "DG19" smd circle
			(at -22.77491 13.337286 270)
			(size 0.4318 0.4318)
			(layers "F.Cu" "F.Mask" "F.Paste")
			(net "M_H_CPU1_SB_DQ<27>")
		)
		(pad "DG21" smd circle
			(at -21.147278 13.337286 270)
			(size 0.4318 0.4318)
			(layers "F.Cu" "F.Mask" "F.Paste")
			(net "GND")
		)
		(pad "DG23" smd circle
			(at -19.519392 13.337286 270)
			(size 0.4318 0.4318)
			(layers "F.Cu" "F.Mask" "F.Paste")
			(net "M_H_CPU1_SB_DQ<14>")
		)
		(pad "DG25" smd circle
			(at -17.89176 13.337286 270)
			(size 0.4318 0.4318)
			(layers "F.Cu" "F.Mask" "F.Paste")
			(net "M_H_CPU1_SB_DQ<11>")
		)
		(pad "DG27" smd circle
			(at -16.263874 13.337286 270)
			(size 0.4318 0.4318)
			(layers "F.Cu" "F.Mask" "F.Paste")
			(net "GND")
		)
		(pad "DG29" smd circle
			(at -14.635988 13.337286 270)
			(size 0.4318 0.4318)
			(layers "F.Cu" "F.Mask" "F.Paste")
			(net "M_H_CPU1_SB_DQ<6>")
		)
		(pad "DG31" smd circle
			(at -13.008356 13.337286 270)
			(size 0.4318 0.4318)
			(layers "F.Cu" "F.Mask" "F.Paste")
			(net "M_H_CPU1_SB_DQ<3>")
		)
		(pad "DG33" smd circle
			(at -11.380724 13.337286 270)
			(size 0.4318 0.4318)
			(layers "F.Cu" "F.Mask" "F.Paste")
			(net "GND")
		)
		(pad "DG35" smd circle
			(at -9.752838 13.337286 270)
			(size 0.4318 0.4318)
			(layers "F.Cu" "F.Mask" "F.Paste")
			(net "M_H_CPU1_SB_CB<2>")
		)
		(pad "DG37" smd circle
			(at -8.124952 13.337286 270)
			(size 0.4318 0.4318)
			(layers "F.Cu" "F.Mask" "F.Paste")
			(net "M_H_CPU1_SB_CB<5>")
		)
		(pad "DG39" smd circle
			(at -6.49732 13.337286 270)
			(size 0.4318 0.4318)
			(layers "F.Cu" "F.Mask" "F.Paste")
			(net "GND")
		)
		(pad "DG41" smd circle
			(at -4.869434 13.337286 270)
			(size 0.4318 0.4318)
			(layers "F.Cu" "F.Mask" "F.Paste")
			(net "M_H_CPU1_SB_CA<1>")
		)
		(pad "DG43" smd circle
			(at -3.241802 13.337286 270)
			(size 0.4318 0.4318)
			(layers "F.Cu" "F.Mask" "F.Paste")
			(net "M_E_CPU1_SB_RSP<1>")
		)
		(pad "DG45" smd circle
			(at -1.613916 13.337286 270)
			(size 0.4318 0.4318)
			(layers "F.Cu" "F.Mask" "F.Paste")
			(net "GND")
		)
		(pad "DG48" smd circle
			(at 2.427732 13.447268 270)
			(size 0.4318 0.4318)
			(layers "F.Cu" "F.Mask" "F.Paste")
			(net "M_H_CPU1_SA_CA<3>")
		)
		(pad "DG50" smd circle
			(at 4.055618 13.447268 270)
			(size 0.4318 0.4318)
			(layers "F.Cu" "F.Mask" "F.Paste")
			(net "M_H_CPU1_SA_CS_N<1>")
		)
		(pad "DG52" smd circle
			(at 5.68325 13.447268 270)
			(size 0.4318 0.4318)
			(layers "F.Cu" "F.Mask" "F.Paste")
			(net "GND")
		)
		(pad "DG54" smd circle
			(at 7.311136 13.447268 270)
			(size 0.4318 0.4318)
			(layers "F.Cu" "F.Mask" "F.Paste")
			(net "M_H_CPU1_SA_CB<6>")
		)
		(pad "DG56" smd circle
			(at 8.939022 13.447268 270)
			(size 0.4318 0.4318)
			(layers "F.Cu" "F.Mask" "F.Paste")
			(net "M_H_CPU1_SA_CB<3>")
		)
		(pad "DG58" smd circle
			(at 10.566654 13.447268 270)
			(size 0.4318 0.4318)
			(layers "F.Cu" "F.Mask" "F.Paste")
			(net "GND")
		)
		(pad "DG60" smd circle
			(at 12.19454 13.447268 270)
			(size 0.4318 0.4318)
			(layers "F.Cu" "F.Mask" "F.Paste")
			(net "M_H_CPU1_SA_DQ<30>")
		)
		(pad "DG62" smd circle
			(at 13.822426 13.447268 270)
			(size 0.4318 0.4318)
			(layers "F.Cu" "F.Mask" "F.Paste")
			(net "M_H_CPU1_SA_DQ<27>")
		)
		(pad "DG64" smd circle
			(at 15.450058 13.447268 270)
			(size 0.4318 0.4318)
			(layers "F.Cu" "F.Mask" "F.Paste")
			(net "GND")
		)
		(pad "DG66" smd circle
			(at 17.07769 13.447268 270)
			(size 0.4318 0.4318)
			(layers "F.Cu" "F.Mask" "F.Paste")
			(net "M_H_CPU1_SA_DQ<22>")
		)
		(pad "DG68" smd circle
			(at 18.705576 13.447268 270)
			(size 0.4318 0.4318)
			(layers "F.Cu" "F.Mask" "F.Paste")
			(net "M_H_CPU1_SA_DQ<19>")
		)
	)
)
